(kicad_pcb
	(version 20260206)
	(generator "pcbnew")
	(generator_version "10.0")
	(general
		(thickness 1.6)
		(legacy_teardrops no)
	)
	(paper "A4")
	(title_block
		(title "Bryce Canyon_F.DPB_16315-1-OCP.brd")
		(comment 1 "Bryce Canyon / footprints 38-41 of 2223")
	)
	(layers
		(0 "F.Cu" signal "TOP")
		(4 "In1.Cu" signal "L2GND")
		(6 "In2.Cu" signal "L3")
		(8 "In3.Cu" signal "L4GND")
		(10 "In4.Cu" signal "L5")
		(12 "In5.Cu" signal "L6VCC")
		(14 "In6.Cu" signal "L7VCC")
		(16 "In7.Cu" signal "L8")
		(18 "In8.Cu" signal "L9GND")
		(20 "In9.Cu" signal "L10")
		(22 "In10.Cu" signal "L11GND")
		(2 "B.Cu" signal "BOTTOM")
		(9 "F.Adhes" user "F.Adhesive")
		(11 "B.Adhes" user "B.Adhesive")
		(13 "F.Paste" user "Package Geometry/Pastemask Top")
		(15 "B.Paste" user "Package Geometry/Pastemask Bottom")
		(5 "F.SilkS" user "Ref Des/Silkscreen Top")
		(7 "B.SilkS" user "Ref Des/Silkscreen Bottom")
		(1 "F.Mask" user "Board Geometry/Soldermask Top")
		(3 "B.Mask" user "Board Geometry/Soldermask Bottom")
		(17 "Dwgs.User" user "User.Drawings")
		(19 "Cmts.User" user "User.Comments")
		(21 "Eco1.User" user "User.Eco1")
		(23 "Eco2.User" user "User.Eco2")
		(25 "Edge.Cuts" user "Board Geometry/Outline")
		(27 "Margin" user)
		(31 "F.CrtYd" user "Package Geometry/Place Bound Top")
		(29 "B.CrtYd" user "Package Geometry/Place Bound Bottom")
		(35 "F.Fab" user "Ref Des/Assembly Top")
		(33 "B.Fab" user "Ref Des/Assembly Bottom")
	)
	(footprint ""
		(layer "F.Cu")
		(at 261.112 -272.288 180)
		(property "Reference" "R102"
			(at 0 0 180)
			(layer "F.SilkS")
			(hide yes)
			(effects
				(font
					(size 1.27 1.27)
				)
			)
		)
		(property "Value" "4K7R2F-GP"
			(at 0.064008 -3.993896 180)
			(unlocked yes)
			(layer "F.Fab")
			(hide yes)
			(effects
				(font
					(size 1.016 1.016)
					(thickness 0.1524)
				)
			)
		)
		(property "Device Type" "R402H16"
			(at 0.064008 -5.517896 180)
			(unlocked yes)
			(layer "F.Fab")
			(hide yes)
			(effects
				(font
					(size 1.016 1.016)
					(thickness 0.1524)
				)
			)
		)
		(duplicate_pad_numbers_are_jumpers no)
		(fp_line
			(start 0.508 -0.9398)
			(end -0.508 -0.9398)
			(stroke
				(width 0.1524)
				(type default)
			)
			(layer "F.SilkS")
		)
		(fp_line
			(start -0.508 -0.9398)
			(end -0.508 0.9398)
			(stroke
				(width 0.1524)
				(type default)
			)
			(layer "F.SilkS")
		)
		(fp_rect
			(start -0.508 0.9398)
			(end 0.508 -0.9398)
			(stroke
				(width 0)
				(type default)
			)
			(fill no)
			(layer "F.CrtYd")
		)
		(fp_rect
			(start -0.508 0.9398)
			(end 0.508 -0.9398)
			(stroke
				(width 0)
				(type default)
			)
			(fill no)
			(layer "F.Fab")
		)
		(pad "1" smd custom
			(at 0 -0.4445 180)
			(size 0.1397 0.1397)
			(layers "F.Cu" "F.Mask" "F.Paste")
			(net "P3V3_STBY_A")
			(options
				(clearance outline)
				(anchor circle)
			)
			(primitives
				(gr_poly
					(pts
						(arc
							(start -0.1778 -0.2794)
							(mid -0.249642 -0.249642)
							(end -0.2794 -0.1778)
						)
						(arc
							(start -0.2794 0.1778)
							(mid -0.249642 0.249642)
							(end -0.1778 0.2794)
						)
						(arc
							(start 0.1778 0.2794)
							(mid 0.249642 0.249642)
							(end 0.2794 0.1778)
						)
						(arc
							(start 0.2794 -0.1778)
							(mid 0.249642 -0.249642)
							(end 0.1778 -0.2794)
						)
					)
					(width 0)
					(fill yes)
				)
			)
		)
		(pad "2" smd custom
			(at 0 0.4445 180)
			(size 0.1397 0.1397)
			(layers "F.Cu" "F.Mask" "F.Paste")
			(net "IO_EXP0_HDD_FAULT_A1")
			(options
				(clearance outline)
				(anchor circle)
			)
			(primitives
				(gr_poly
					(pts
						(arc
							(start -0.1778 -0.2794)
							(mid -0.249642 -0.249642)
							(end -0.2794 -0.1778)
						)
						(arc
							(start -0.2794 0.1778)
							(mid -0.249642 0.249642)
							(end -0.1778 0.2794)
						)
						(arc
							(start 0.1778 0.2794)
							(mid 0.249642 0.249642)
							(end 0.2794 0.1778)
						)
						(arc
							(start 0.2794 -0.1778)
							(mid 0.249642 -0.249642)
							(end 0.1778 -0.2794)
						)
					)
					(width 0)
					(fill yes)
				)
			)
		)
	)
	(footprint ""
		(layer "F.Cu")
		(at 158.342838 -27.338782 -90)
		(property "Reference" "R11"
			(at 0 0 270)
			(layer "F.SilkS")
			(hide yes)
			(effects
				(font
					(size 1.27 1.27)
				)
			)
		)
		(property "Value" "0R2J-2-GP"
			(at 0.064008 -3.993896 270)
			(unlocked yes)
			(layer "F.Fab")
			(hide yes)
			(effects
				(font
					(size 1.016 1.016)
					(thickness 0.1524)
				)
			)
		)
		(property "Device Type" "R402H16"
			(at 0.064008 -5.517896 270)
			(unlocked yes)
			(layer "F.Fab")
			(hide yes)
			(effects
				(font
					(size 1.016 1.016)
					(thickness 0.1524)
				)
			)
		)
		(duplicate_pad_numbers_are_jumpers no)
		(fp_line
			(start -0.508 -0.9398)
			(end -0.508 0.9398)
			(stroke
				(width 0.1524)
				(type default)
			)
			(layer "F.SilkS")
		)
		(fp_line
			(start 0.508 -0.9398)
			(end -0.508 -0.9398)
			(stroke
				(width 0.1524)
				(type default)
			)
			(layer "F.SilkS")
		)
		(fp_rect
			(start -0.508 0.9398)
			(end 0.508 -0.9398)
			(stroke
				(width 0)
				(type default)
			)
			(fill no)
			(layer "F.CrtYd")
		)
		(fp_rect
			(start -0.508 0.9398)
			(end 0.508 -0.9398)
			(stroke
				(width 0)
				(type default)
			)
			(fill no)
			(layer "F.Fab")
		)
		(pad "1" smd custom
			(at 0 -0.4445 270)
			(size 0.1397 0.1397)
			(layers "F.Cu" "F.Mask" "F.Paste")
			(net "GND")
			(options
				(clearance outline)
				(anchor circle)
			)
			(primitives
				(gr_poly
					(pts
						(arc
							(start -0.1778 -0.2794)
							(mid -0.249642 -0.249642)
							(end -0.2794 -0.1778)
						)
						(arc
							(start -0.2794 0.1778)
							(mid -0.249642 0.249642)
							(end -0.1778 0.2794)
						)
						(arc
							(start 0.1778 0.2794)
							(mid 0.249642 0.249642)
							(end 0.2794 0.1778)
						)
						(arc
							(start 0.2794 -0.1778)
							(mid 0.249642 -0.249642)
							(end 0.1778 -0.2794)
						)
					)
					(width 0)
					(fill yes)
				)
			)
		)
		(pad "2" smd custom
			(at 0 0.4445 270)
			(size 0.1397 0.1397)
			(layers "F.Cu" "F.Mask" "F.Paste")
			(net "IOM_A_MATED_N")
			(options
				(clearance outline)
				(anchor circle)
			)
			(primitives
				(gr_poly
					(pts
						(arc
							(start -0.1778 -0.2794)
							(mid -0.249642 -0.249642)
							(end -0.2794 -0.1778)
						)
						(arc
							(start -0.2794 0.1778)
							(mid -0.249642 0.249642)
							(end -0.1778 0.2794)
						)
						(arc
							(start 0.1778 0.2794)
							(mid 0.249642 0.249642)
							(end 0.2794 0.1778)
						)
						(arc
							(start 0.2794 -0.1778)
							(mid 0.249642 -0.249642)
							(end 0.1778 -0.2794)
						)
					)
					(width 0)
					(fill yes)
				)
			)
		)
	)
	(footprint ""
		(layer "F.Cu")
		(at 86.121748 -276.040342 -90)
		(property "Reference" "R184"
			(at 0 0 270)
			(layer "F.SilkS")
			(hide yes)
			(effects
				(font
					(size 1.27 1.27)
				)
			)
		)
		(property "Value" "1KR2F-3-GP"
			(at 0.064008 -3.993896 270)
			(unlocked yes)
			(layer "F.Fab")
			(hide yes)
			(effects
				(font
					(size 1.016 1.016)
					(thickness 0.1524)
				)
			)
		)
		(property "Device Type" "R402H16"
			(at 0.064008 -5.517896 270)
			(unlocked yes)
			(layer "F.Fab")
			(hide yes)
			(effects
				(font
					(size 1.016 1.016)
					(thickness 0.1524)
				)
			)
		)
		(duplicate_pad_numbers_are_jumpers no)
		(fp_line
			(start -0.508 -0.9398)
			(end -0.508 0.9398)
			(stroke
				(width 0.1524)
				(type default)
			)
			(layer "F.SilkS")
		)
		(fp_line
			(start 0.508 -0.9398)
			(end -0.508 -0.9398)
			(stroke
				(width 0.1524)
				(type default)
			)
			(layer "F.SilkS")
		)
		(fp_rect
			(start -0.508 0.9398)
			(end 0.508 -0.9398)
			(stroke
				(width 0)
				(type default)
			)
			(fill no)
			(layer "F.CrtYd")
		)
		(fp_rect
			(start -0.508 0.9398)
			(end 0.508 -0.9398)
			(stroke
				(width 0)
				(type default)
			)
			(fill no)
			(layer "F.Fab")
		)
		(pad "1" smd custom
			(at 0 -0.4445 270)
			(size 0.1397 0.1397)
			(layers "F.Cu" "F.Mask" "F.Paste")
			(net "P3V3_STBY_A")
			(options
				(clearance outline)
				(anchor circle)
			)
			(primitives
				(gr_poly
					(pts
						(arc
							(start -0.1778 -0.2794)
							(mid -0.249642 -0.249642)
							(end -0.2794 -0.1778)
						)
						(arc
							(start -0.2794 0.1778)
							(mid -0.249642 0.249642)
							(end -0.1778 0.2794)
						)
						(arc
							(start 0.1778 0.2794)
							(mid 0.249642 0.249642)
							(end 0.2794 0.1778)
						)
						(arc
							(start 0.2794 -0.1778)
							(mid 0.249642 -0.249642)
							(end 0.1778 -0.2794)
						)
					)
					(width 0)
					(fill yes)
				)
			)
		)
		(pad "2" smd custom
			(at 0 0.4445 270)
			(size 0.1397 0.1397)
			(layers "F.Cu" "F.Mask" "F.Paste")
			(net "SW_PWR_R_HDD2")
			(options
				(clearance outline)
				(anchor circle)
			)
			(primitives
				(gr_poly
					(pts
						(arc
							(start -0.1778 -0.2794)
							(mid -0.249642 -0.249642)
							(end -0.2794 -0.1778)
						)
						(arc
							(start -0.2794 0.1778)
							(mid -0.249642 0.249642)
							(end -0.1778 0.2794)
						)
						(arc
							(start 0.1778 0.2794)
							(mid 0.249642 0.249642)
							(end 0.2794 0.1778)
						)
						(arc
							(start 0.2794 -0.1778)
							(mid 0.249642 -0.249642)
							(end 0.1778 -0.2794)
						)
					)
					(width 0)
					(fill yes)
				)
			)
		)
	)
	(footprint ""
		(layer "F.Cu")
		(at 332.105 -160.252918 -90)
		(property "Reference" "Q109"
			(at 0 0 270)
			(layer "F.SilkS")
			(hide yes)
			(effects
				(font
					(size 1.27 1.27)
				)
			)
		)
		(property "Value" "2N7002KDW-GP"
			(at -2.3622 -8.2042 270)
			(unlocked yes)
			(layer "F.Fab")
			(hide yes)
			(effects
				(font
					(size 1.016 1.016)
					(thickness 0.1524)
				)
			)
		)
		(property "Device Type" "SOT-363H44"
			(at -2.3622 -10.1092 270)
			(unlocked yes)
			(layer "F.Fab")
			(hide yes)
			(effects
				(font
					(size 1.016 1.016)
					(thickness 0.1524)
				)
			)
		)
		(duplicate_pad_numbers_are_jumpers no)
		(fp_line
			(start -1.4478 1.7018)
			(end 1.4478 1.7018)
			(stroke
				(width 0.1524)
				(type default)
			)
			(layer "F.SilkS")
		)
		(fp_line
			(start 1.4478 1.7018)
			(end 1.4478 -1.7018)
			(stroke
				(width 0.1524)
				(type default)
			)
			(layer "F.SilkS")
		)
		(fp_line
			(start -1.27 1.524)
			(end -1.27 0.6604)
			(stroke
				(width 0.4826)
				(type default)
			)
			(layer "F.SilkS")
		)
		(fp_line
			(start -1.4478 -1.7018)
			(end -1.4478 1.7018)
			(stroke
				(width 0.1524)
				(type default)
			)
			(layer "F.SilkS")
		)
		(fp_line
			(start 1.4478 -1.7018)
			(end -1.4478 -1.7018)
			(stroke
				(width 0.1524)
				(type default)
			)
			(layer "F.SilkS")
		)
		(fp_poly
			(pts
				(xy -1.524 -1.778) (xy 1.524 -1.778) (xy 1.524 1.778) (xy -1.524 1.778)
			)
			(stroke
				(width 0)
				(type default)
			)
			(fill no)
			(layer "F.CrtYd")
		)
		(fp_poly
			(pts
				(xy -1.524 -1.778) (xy 1.524 -1.778) (xy 1.524 1.778) (xy -1.524 1.778)
			)
			(stroke
				(width 0)
				(type default)
			)
			(fill no)
			(layer "F.Fab")
		)
		(pad "1" smd rect
			(at -0.65024 0.9398 270)
			(size 0.4064 1.016)
			(layers "F.Cu" "F.Mask" "F.Paste")
			(net "GND")
		)
		(pad "2" smd rect
			(at 0 0.9398 270)
			(size 0.4064 1.016)
			(layers "F.Cu" "F.Mask" "F.Paste")
			(net "SW_PWR_R_HDD18")
		)
		(pad "3" smd rect
			(at 0.65024 0.9398 270)
			(size 0.4064 1.016)
			(layers "F.Cu" "F.Mask" "F.Paste")
			(net "SW_HDD_P18")
		)
		(pad "4" smd rect
			(at 0.65024 -0.9398 270)
			(size 0.4064 1.016)
			(layers "F.Cu" "F.Mask" "F.Paste")
			(net "GND")
		)
		(pad "5" smd rect
			(at 0 -0.9398 270)
			(size 0.4064 1.016)
			(layers "F.Cu" "F.Mask" "F.Paste")
			(net "SW_HDD_G18")
		)
		(pad "6" smd rect
			(at -0.65024 -0.9398 270)
			(size 0.4064 1.016)
			(layers "F.Cu" "F.Mask" "F.Paste")
			(net "SW_HDD_R18")
		)
	)
)
